FILE_TYPE = CONNECTIVITY;
{Allegro Design Entry HDL 17.2-2016 S081 (4005846) 1/11/2022}
"PAGE_NUMBER" = 106;
0"NC";
1"M_J_CPU1_SB_DQS_DP<9:0>";
2"M_J_CPU1_SB_DQS_DN<9:0>";
3"M_J_CPU1_SA_DQS_DP<9:0>";
4"M_J_CPU1_SA_DQS_DN<9:0>";
5"M_J_CPU1_SA_DQ<31:0>";
6"M_J_CPU1_SA_CA<6:0>";
7"M_J_CPU1_SB_DQ<31:0>";
8"M_J_CPU1_SB_CB<7:0>";
9"M_J_CPU1_SA_CB<7:0>";
10"M_J_CPU1_SB_CA<6:0>";
11"GND\g";
12"GND\g";
13"P3V3_STBY\g";
14"I3C_SPD_DDRGL_CPU1_SCL";
15"PWRGD_CHJ_CPU1_DIMM";
16"I3C_SPD_DDRJ_CPU1_SCL";
17"I3C_SPD_DDRGL_CPU1_SDA";
18"PD_CHJ_CPU1_DIMM_SAA";
19"M_J_CPU1_SA_RSP<0>";
20"TP_CHJ_CPU1_DIMM_RFU_0";
21"TP_CHJ_CPU1_DIMM_RFU_1";
22"TP_CHJ_CPU1_DIMM_RFU_3";
23"TP_CHJ_CPU1_DIMM_RFU_4";
24"TP_CHJ_CPU1_DIMM_RFU_5";
25"TP_CHJ_CPU1_DIMM_RFU_6";
26"M_J_CPU1_SB_DQ<11>";
27"P3V3_STBY\g";
28"M_J_CPU1_ALERT_N";
29"M_J_CPU1_RESET_N";
30"GND\g";
31"PD_CHJ_CPU1_DIMM_SAA";
32"PWRGD_CHGL_CPU1";
33"M_J_CPU1_SA_DQ<31>";
34"M_J_CPU1_SA_CB<7>";
35"M_J_CPU1_SA_CB<4>";
36"M_J_CPU1_SA_CB<1>";
37"M_J_CPU1_SB_CB<7>";
38"M_J_CPU1_SA_CA<0>";
39"M_J_CPU1_SB_CA<0>";
40"M_J_CPU1_SA_CA<1>";
41"M_J_CPU1_SB_CA<1>";
42"M_J_CPU1_SA_CA<2>";
43"M_J_CPU1_SB_CA<2>";
44"M_J_CPU1_SB_CA<3>";
45"M_J_CPU1_SA_CA<4>";
46"M_J_CPU1_SB_CA<4>";
47"M_J_CPU1_SB_CA<5>";
48"M_J_CPU1_SB_CA<6>";
49"M_J_CPU1_SA_CB<6>";
50"M_J_CPU1_SA_CB<5>";
51"M_J_CPU1_SA_CB<3>";
52"M_J_CPU1_SA_CB<2>";
53"M_J_CPU1_SA_CB<0>";
54"M_J_CPU1_SB_CB<6>";
55"M_J_CPU1_SB_CB<5>";
56"M_J_CPU1_SB_CB<4>";
57"M_J_CPU1_SB_CB<3>";
58"M_J_CPU1_SB_CB<2>";
59"M_J_CPU1_SB_CB<1>";
60"M_J_CPU1_SB_CB<0>";
61"M_J_CPU1_CLK_DN<0>";
62"M_J_CPU1_CLK_DP<0>";
63"M_J_CPU1_SB_CS_N<0>";
64"M_J_CPU1_SA_CS_N<1>";
65"M_J_CPU1_SB_CS_N<1>";
66"M_J_CPU1_SA_DQ<30>";
67"M_J_CPU1_SA_DQ<28>";
68"M_J_CPU1_SA_DQ<27>";
69"M_J_CPU1_SA_DQ<26>";
70"M_J_CPU1_SA_DQ<25>";
71"M_J_CPU1_SA_DQ<20>";
72"M_J_CPU1_SA_DQ<19>";
73"M_J_CPU1_SA_DQ<18>";
74"M_J_CPU1_SA_DQ<17>";
75"M_J_CPU1_SA_DQ<16>";
76"M_J_CPU1_SA_DQ<14>";
77"M_J_CPU1_SA_DQ<13>";
78"M_J_CPU1_SA_DQ<12>";
79"M_J_CPU1_SA_DQ<11>";
80"M_J_CPU1_SA_DQ<10>";
81"M_J_CPU1_SA_DQ<9>";
82"M_J_CPU1_SA_DQ<8>";
83"M_J_CPU1_SA_DQ<7>";
84"M_J_CPU1_SA_DQ<6>";
85"M_J_CPU1_SA_DQ<5>";
86"M_J_CPU1_SA_DQ<4>";
87"M_J_CPU1_SA_DQ<3>";
88"M_J_CPU1_SA_DQ<2>";
89"M_J_CPU1_SA_DQ<1>";
90"M_J_CPU1_SA_DQ<0>";
91"M_J_CPU1_SB_DQ<31>";
92"M_J_CPU1_SB_DQ<30>";
93"M_J_CPU1_SB_DQ<29>";
94"M_J_CPU1_SB_DQ<28>";
95"M_J_CPU1_SB_DQ<27>";
96"M_J_CPU1_SB_DQ<26>";
97"M_J_CPU1_SB_DQ<25>";
98"M_J_CPU1_SB_DQ<24>";
99"M_J_CPU1_SB_DQ<23>";
100"M_J_CPU1_SB_DQ<22>";
101"M_J_CPU1_SB_DQ<21>";
102"M_J_CPU1_SB_DQ<19>";
103"M_J_CPU1_SB_DQ<17>";
104"M_J_CPU1_SB_DQ<16>";
105"M_J_CPU1_SB_DQ<15>";
106"M_J_CPU1_SB_DQ<14>";
107"M_J_CPU1_SB_DQ<13>";
108"M_J_CPU1_SB_DQ<12>";
109"M_J_CPU1_SB_DQ<10>";
110"M_J_CPU1_SB_DQ<9>";
111"M_J_CPU1_SB_DQ<8>";
112"M_J_CPU1_SB_DQ<7>";
113"M_J_CPU1_SB_DQ<6>";
114"M_J_CPU1_SB_DQ<5>";
115"M_J_CPU1_SB_DQ<4>";
116"M_J_CPU1_SB_DQ<3>";
117"M_J_CPU1_SB_DQ<2>";
118"M_J_CPU1_SB_DQ<1>";
119"M_J_CPU1_SB_DQ<0>";
120"M_J_CPU1_SB_RSP<0>";
121"M_J_CPU1_SA_PAR";
122"M_J_CPU1_SB_PAR";
123"M_J_CPU1_SA_DQ<29>";
124"M_J_CPU1_SA_DQ<21>";
125"M_J_CPU1_SA_DQ<22>";
126"M_J_CPU1_SA_CA<3>";
127"M_J_CPU1_SA_CA<5>";
128"M_J_CPU1_SA_CA<6>";
129"M_J_CPU1_SA_DQ<24>";
130"M_J_CPU1_SA_DQ<23>";
131"M_J_CPU1_SA_DQ<15>";
132"M_J_CPU1_SA_DQS_DN<7>";
133"M_J_CPU1_SA_DQS_DP<6>";
134"M_J_CPU1_SB_DQS_DP<8>";
135"M_J_CPU1_SB_DQS_DN<8>";
136"M_J_CPU1_SB_DQS_DP<7>";
137"M_J_CPU1_SA_DQS_DN<0>";
138"M_J_CPU1_SA_DQS_DP<0>";
139"M_J_CPU1_SB_DQS_DN<0>";
140"M_J_CPU1_SB_DQS_DP<0>";
141"M_J_CPU1_SA_DQS_DN<1>";
142"M_J_CPU1_SA_DQS_DP<1>";
143"M_J_CPU1_SB_DQS_DN<1>";
144"M_J_CPU1_SB_DQS_DP<1>";
145"M_J_CPU1_SA_DQS_DN<2>";
146"M_J_CPU1_SA_DQS_DP<2>";
147"M_J_CPU1_SB_DQS_DN<2>";
148"M_J_CPU1_SB_DQS_DP<2>";
149"M_J_CPU1_SA_DQS_DN<3>";
150"M_J_CPU1_SA_DQS_DP<3>";
151"M_J_CPU1_SB_DQS_DN<3>";
152"M_J_CPU1_SB_DQS_DP<3>";
153"M_J_CPU1_SA_DQS_DN<4>";
154"M_J_CPU1_SA_DQS_DP<4>";
155"M_J_CPU1_SB_DQS_DN<4>";
156"M_J_CPU1_SB_DQS_DP<4>";
157"M_J_CPU1_SA_DQS_DN<5>";
158"M_J_CPU1_SA_DQS_DP<5>";
159"M_J_CPU1_SB_DQS_DN<5>";
160"M_J_CPU1_SB_DQS_DP<5>";
161"M_J_CPU1_SA_DQS_DN<6>";
162"M_J_CPU1_SB_DQS_DN<6>";
163"M_J_CPU1_SB_DQS_DP<6>";
164"M_J_CPU1_SA_DQS_DP<7>";
165"M_J_CPU1_SB_DQS_DN<7>";
166"M_J_CPU1_SA_DQS_DN<8>";
167"M_J_CPU1_SA_DQS_DP<8>";
168"M_J_CPU1_SB_DQS_DN<9>";
169"M_J_CPU1_SB_DQS_DP<9>";
170"M_J_CPU1_SA_DQS_DN<9>";
171"M_J_CPU1_SA_DQS_DP<9>";
172"P12V_MEM_1\g";
173"GND\g";
174"GND\g";
175"M_J_CPU1_SA_CS_N<0>";
176"M_J_CPU1_SB_DQ<20>";
177"M_J_CPU1_SB_DQ<18>";
178"TP_CHJ_CPU1_DIMM_RFU_2";
%"TAP"
"1","(-5850,4125)","0","mstr_standard","I100";
;
CDS_LIB"mstr_standard"
BODY_TYPE"PLUMBING"
HDL_TAP"TRUE";
"B \NAC \NWC"5;
"S \NAC"
BN"7"83;
%"TAP"
"1","(-5850,4175)","0","mstr_standard","I101";
;
CDS_LIB"mstr_standard"
BODY_TYPE"PLUMBING"
HDL_TAP"TRUE";
"B \NAC \NWC"5;
"S \NAC"
BN"8"82;
%"TAP"
"1","(-5850,4225)","0","mstr_standard","I102";
;
CDS_LIB"mstr_standard"
BODY_TYPE"PLUMBING"
HDL_TAP"TRUE";
"B \NAC \NWC"5;
"S \NAC"
BN"9"81;
%"TAP"
"1","(-5850,4275)","0","mstr_standard","I103";
;
CDS_LIB"mstr_standard"
BODY_TYPE"PLUMBING"
HDL_TAP"TRUE";
"B \NAC \NWC"5;
"S \NAC"
BN"10"80;
%"TAP"
"1","(-5850,4375)","0","mstr_standard","I104";
;
CDS_LIB"mstr_standard"
BODY_TYPE"PLUMBING"
HDL_TAP"TRUE";
"B \NAC \NWC"5;
"S \NAC"
BN"12"78;
%"TAP"
"1","(-5850,4325)","0","mstr_standard","I105";
;
CDS_LIB"mstr_standard"
BODY_TYPE"PLUMBING"
HDL_TAP"TRUE";
"B \NAC \NWC"5;
"S \NAC"
BN"11"79;
%"TAP"
"1","(-5850,4425)","0","mstr_standard","I106";
;
CDS_LIB"mstr_standard"
BODY_TYPE"PLUMBING"
HDL_TAP"TRUE";
"B \NAC \NWC"5;
"S \NAC"
BN"13"77;
%"TAP"
"1","(-5850,4475)","0","mstr_standard","I107";
;
CDS_LIB"mstr_standard"
BODY_TYPE"PLUMBING"
HDL_TAP"TRUE";
"B \NAC \NWC"5;
"S \NAC"
BN"14"76;
%"TAP"
"1","(-5850,4525)","0","mstr_standard","I108";
;
CDS_LIB"mstr_standard"
BODY_TYPE"PLUMBING"
HDL_TAP"TRUE";
"B \NAC \NWC"5;
"S \NAC"
BN"15"131;
%"TAP"
"1","(-5850,4575)","0","mstr_standard","I109";
;
CDS_LIB"mstr_standard"
BODY_TYPE"PLUMBING"
HDL_TAP"TRUE";
"B \NAC \NWC"5;
"S \NAC"
BN"16"75;
%"TAP"
"1","(-5850,4625)","0","mstr_standard","I110";
;
CDS_LIB"mstr_standard"
BODY_TYPE"PLUMBING"
HDL_TAP"TRUE";
"B \NAC \NWC"5;
"S \NAC"
BN"17"74;
%"TAP"
"1","(-5850,4675)","0","mstr_standard","I111";
;
CDS_LIB"mstr_standard"
BODY_TYPE"PLUMBING"
HDL_TAP"TRUE";
"B \NAC \NWC"5;
"S \NAC"
BN"18"73;
%"TAP"
"1","(-5850,4725)","0","mstr_standard","I112";
;
CDS_LIB"mstr_standard"
BODY_TYPE"PLUMBING"
HDL_TAP"TRUE";
"B \NAC \NWC"5;
"S \NAC"
BN"19"72;
%"TAP"
"1","(-5850,4775)","0","mstr_standard","I113";
;
CDS_LIB"mstr_standard"
BODY_TYPE"PLUMBING"
HDL_TAP"TRUE";
"B \NAC \NWC"5;
"S \NAC"
BN"20"71;
%"TAP"
"1","(-5850,4825)","0","mstr_standard","I114";
;
CDS_LIB"mstr_standard"
BODY_TYPE"PLUMBING"
HDL_TAP"TRUE";
"B \NAC \NWC"5;
"S \NAC"
BN"21"124;
%"TAP"
"1","(-5850,4875)","0","mstr_standard","I115";
;
CDS_LIB"mstr_standard"
BODY_TYPE"PLUMBING"
HDL_TAP"TRUE";
"B \NAC \NWC"5;
"S \NAC"
BN"22"125;
%"TAP"
"1","(-5850,4925)","0","mstr_standard","I116";
;
CDS_LIB"mstr_standard"
BODY_TYPE"PLUMBING"
HDL_TAP"TRUE";
"B \NAC \NWC"5;
"S \NAC"
BN"23"130;
%"TAP"
"1","(-5850,4975)","0","mstr_standard","I117";
;
CDS_LIB"mstr_standard"
BODY_TYPE"PLUMBING"
HDL_TAP"TRUE";
"B \NAC \NWC"5;
"S \NAC"
BN"24"129;
%"TAP"
"1","(-5850,5025)","0","mstr_standard","I118";
;
CDS_LIB"mstr_standard"
BODY_TYPE"PLUMBING"
HDL_TAP"TRUE";
"B \NAC \NWC"5;
"S \NAC"
BN"25"70;
%"TAP"
"1","(-5850,5075)","0","mstr_standard","I119";
;
CDS_LIB"mstr_standard"
BODY_TYPE"PLUMBING"
HDL_TAP"TRUE";
"B \NAC \NWC"5;
"S \NAC"
BN"26"69;
%"TAP"
"1","(-5850,5125)","0","mstr_standard","I120";
;
CDS_LIB"mstr_standard"
BODY_TYPE"PLUMBING"
HDL_TAP"TRUE";
"B \NAC \NWC"5;
"S \NAC"
BN"27"68;
%"TAP"
"1","(-5850,5175)","0","mstr_standard","I121";
;
CDS_LIB"mstr_standard"
BODY_TYPE"PLUMBING"
HDL_TAP"TRUE";
"B \NAC \NWC"5;
"S \NAC"
BN"28"67;
%"TAP"
"1","(-5850,5275)","0","mstr_standard","I122";
;
CDS_LIB"mstr_standard"
BODY_TYPE"PLUMBING"
HDL_TAP"TRUE";
"B \NAC \NWC"5;
"S \NAC"
BN"30"66;
%"TAP"
"1","(-5850,5225)","0","mstr_standard","I123";
;
CDS_LIB"mstr_standard"
BODY_TYPE"PLUMBING"
HDL_TAP"TRUE";
"B \NAC \NWC"5;
"S \NAC"
BN"29"123;
%"TAP"
"1","(-5850,5325)","0","mstr_standard","I124";
;
CDS_LIB"mstr_standard"
BODY_TYPE"PLUMBING"
HDL_TAP"TRUE";
"B \NAC \NWC"5;
"S \NAC"
BN"31"33;
%"GND"
"1","(-6250,950)","0","mstr_symbols","I126";
;
SIZE"1B"
BOM_COST"MEM"
CDS_LIB"mstr_symbols"
BODY_TYPE"PLUMBING"
VOLTAGE"0.0"
HDL_POWER"GND";
"A\NAC"11;
%"Q_RES"
"2","(-6250,1175)","0","pure_quanta","I127";
;
LOCATION"R776"
$SEC"1"
CDS_SEC"1"
WATTAGE"1/16W"
MATERIAL"CHIP"
TOLERANCE"1%"
VALUE"35.7K"
PART_NUMBER"CS33572FB01"
PACK_TYPE"0402LF"
CDS_LIB"pure_quanta";
"A"
$PN"1"31;
"B"
$PN"2"11;
%"GND"
"1","(-2025,1800)","0","mstr_symbols","I128";
;
CDS_LIB"mstr_symbols"
SIZE"1B"
BODY_TYPE"PLUMBING"
VOLTAGE"0.0"
HDL_POWER"GND";
"A\NAC"174;
%"GND"
"1","(-225,1575)","0","mstr_symbols","I142";
;
CDS_LIB"mstr_symbols"
SIZE"1B"
BODY_TYPE"PLUMBING"
VOLTAGE"0.0"
HDL_POWER"GND";
"A\NAC"173;
%"SCONN288_DDR506112002KQ"
"3","(-1125,3575)","0","pure_quanta","I143";
;
LOCATION"J29"
$SEC"3"
CDS_SEC"3"
PART_TYPE"SMLF"
VALUE"SCONN288_DDR506112002KQ"
MATERIAL"IO"
PART_NUMBER"DFHST8FS479"
CDS_LMAN_SYM_OUTLINE"-450,1800,450,-1750"
NEEDS_NO_SIZE"TRUE"
CDS_LIB"pure_quanta";
"G3"
$PN"G3"173;
"G2"
$PN"G2"173;
"G1"
$PN"G1"173;
"VSS62"
$PN"141"173;
"VSS61"
$PN"139"173;
"VSS60"
$PN"136"173;
"VSS58"
$PN"132"173;
"VSS104"
$PN"240"174;
"VSS102"
$PN"235"174;
"VSS100"
$PN"230"174;
"VIN_BULK2"
$PN"146"172;
"VIN_BULK1"
$PN"145"172;
"VIN_BULK0"
$PN"1"172;
"VSS126"
$PN"288"174;
"VSS125"
$PN"286"174;
"VSS124"
$PN"284"174;
"VSS123"
$PN"281"174;
"VSS122"
$PN"279"174;
"VSS121"
$PN"277"174;
"VSS120"
$PN"275"174;
"VSS119"
$PN"273"174;
"VSS118"
$PN"270"174;
"VSS117"
$PN"268"174;
"VSS116"
$PN"266"174;
"VSS115"
$PN"264"174;
"VSS114"
$PN"262"174;
"VSS113"
$PN"259"174;
"VSS112"
$PN"257"174;
"VSS111"
$PN"255"174;
"VSS110"
$PN"253"174;
"VSS109"
$PN"251"174;
"VSS108"
$PN"248"174;
"VSS107"
$PN"246"174;
"VSS106"
$PN"244"174;
"VSS105"
$PN"242"174;
"VSS103"
$PN"237"174;
"VSS101"
$PN"233"174;
"VSS99"
$PN"228"174;
"VSS98"
$PN"226"174;
"VSS97"
$PN"224"174;
"VSS96"
$PN"222"174;
"VSS95"
$PN"219"174;
"VSS94"
$PN"216"174;
"VSS93"
$PN"214"174;
"VSS92"
$PN"212"174;
"VSS91"
$PN"210"174;
"VSS90"
$PN"208"174;
"VSS89"
$PN"206"174;
"VSS88"
$PN"204"174;
"VSS87"
$PN"202"174;
"VSS86"
$PN"199"174;
"VSS85"
$PN"197"174;
"VSS84"
$PN"195"174;
"VSS83"
$PN"193"174;
"VSS82"
$PN"191"174;
"VSS81"
$PN"188"174;
"VSS80"
$PN"186"174;
"VSS79"
$PN"184"174;
"VSS78"
$PN"182"174;
"VSS77"
$PN"180"174;
"VSS76"
$PN"177"174;
"VSS75"
$PN"175"174;
"VSS74"
$PN"173"174;
"VSS73"
$PN"171"174;
"VSS72"
$PN"169"174;
"VSS71"
$PN"166"174;
"VSS70"
$PN"164"174;
"VSS69"
$PN"162"174;
"VSS68"
$PN"160"174;
"VSS67"
$PN"158"174;
"VSS66"
$PN"155"174;
"VSS65"
$PN"153"174;
"VSS64"
$PN"151"174;
"VSS63"
$PN"143"173;
"VSS59"
$PN"134"173;
"VSS57"
$PN"130"173;
"VSS56"
$PN"128"173;
"VSS55"
$PN"125"173;
"VSS54"
$PN"123"173;
"VSS53"
$PN"121"173;
"VSS52"
$PN"119"173;
"VSS51"
$PN"117"173;
"VSS50"
$PN"114"173;
"VSS49"
$PN"112"173;
"VSS48"
$PN"110"173;
"VSS47"
$PN"108"173;
"VSS46"
$PN"106"173;
"VSS45"
$PN"103"173;
"VSS44"
$PN"101"173;
"VSS43"
$PN"99"173;
"VSS42"
$PN"97"173;
"VSS41"
$PN"95"173;
"VSS40"
$PN"92"173;
"VSS39"
$PN"90"173;
"VSS38"
$PN"88"173;
"VSS37"
$PN"85"173;
"VSS36"
$PN"83"173;
"VSS35"
$PN"81"173;
"VSS34"
$PN"79"173;
"VSS33"
$PN"77"173;
"VSS32"
$PN"75"173;
"VSS31"
$PN"73"173;
"VSS30"
$PN"71"173;
"VSS29"
$PN"69"173;
"VSS28"
$PN"67"173;
"VSS27"
$PN"65"173;
"VSS26"
$PN"63"173;
"VSS25"
$PN"61"173;
"VSS24"
$PN"59"173;
"VSS23"
$PN"57"173;
"VSS22"
$PN"54"173;
"VSS21"
$PN"52"173;
"VSS20"
$PN"50"173;
"VSS19"
$PN"48"173;
"VSS18"
$PN"46"173;
"VSS17"
$PN"43"173;
"VSS16"
$PN"41"173;
"VSS15"
$PN"39"173;
"VSS14"
$PN"37"173;
"VSS13"
$PN"35"173;
"VSS12"
$PN"32"173;
"VSS11"
$PN"30"173;
"VSS10"
$PN"28"173;
"VSS9"
$PN"26"173;
"VSS8"
$PN"24"173;
"VSS7"
$PN"21"173;
"VSS6"
$PN"19"173;
"VSS5"
$PN"17"173;
"VSS4"
$PN"15"173;
"VSS3"
$PN"13"173;
"VSS2"
$PN"10"173;
"VSS1"
$PN"8"173;
"VSS0"
$PN"6"173;
%"Q_CAP"
"1","(-8525,3150)","2","pure_quanta","I185";
;
LOCATION"C172"
$SEC"1"
CDS_SEC"1"
MATERIAL"X7R"
TOLERANCE"10%"
VALUE"0.1UF"
PART_NUMBER"CH4104K1B00"
PACK_TYPE"0402"
VOLTAGE"25V"
BOM_COST"MEM"
CDS_LIB"pure_quanta"
ROOM"MEM_CH_A_CPU0_DIMM1";
"B"
$PN"2"12;
"A"
$PN"1"27;
%"GND"
"1","(-8525,2925)","0","mstr_symbols","I186";
;
BOM_COST"MEM"
SIZE"1B"
CDS_LIB"mstr_symbols"
BODY_TYPE"PLUMBING"
VOLTAGE"0"
ROOM"MEM_EFGH_DECOUPLING_CAPS"
HDL_POWER"GND";
"A\NAC"12;
%"Q_RES"
"1","(-8375,2075)","2","pure_quanta","I188";
;
LOCATION"R312"
$SEC"1"
CDS_SEC"1"
VALUE"0"
BOM_COST"MEM"
CDS_LIB"pure_quanta"
WATTAGE"1/16W"
MATERIAL"CHIP"
TOLERANCE"5%"
PART_NUMBER"CS00002JB38"
PACK_TYPE"0402LF"
ROOM"RST_CPU0_PLD_TO_DIMM";
"B"
$PN"2"32;
"A"
$PN"1"15;
%"VCC_CORE"
"1","(-8250,2400)","0","mstr_symbols","I189";
;
HDL_POWER"P3V3_STBY"
CDS_LIB"mstr_symbols"
VOLTAGE"3.3"
ROOM"PVCCINFAON_CPU0_CTRL";
"A"13;
%"Q_RES"
"2","(-8250,2225)","0","pure_quanta","I190";
;
LOCATION"R113"
$SEC"1"
CDS_SEC"1"
VALUE"1K"
TOLERANCE"5%"
MATERIAL"EMPTY"
PACK_TYPE"0402LF"
WATTAGE"1/16W"
BOM_COST"MEM"
CDS_LIB"pure_quanta"
PART_NUMBER"TMP_QCS21002JB34"
ROOM"MEM_CH_A_CPU0_DIMM1";
"A"
$PN"1"13;
"B"
$PN"2"15;
%"TAP"
"1","(-3150,4600)","0","mstr_standard","I196";
;
CDS_LIB"mstr_standard"
BODY_TYPE"PLUMBING"
HDL_TAP"TRUE";
"B \NAC \NWC"4;
"S \NAC"
BN"9"170;
%"TAP"
"1","(-3350,4650)","0","mstr_standard","I197";
;
CDS_LIB"mstr_standard"
BODY_TYPE"PLUMBING"
HDL_TAP"TRUE";
"B \NAC \NWC"3;
"S \NAC"
BN"9"171;
%"TAP"
"1","(-3350,4550)","0","mstr_standard","I198";
;
CDS_LIB"mstr_standard"
BODY_TYPE"PLUMBING"
HDL_TAP"TRUE";
"B \NAC \NWC"3;
"S \NAC"
BN"8"167;
%"TAP"
"1","(-3150,4500)","0","mstr_standard","I199";
;
CDS_LIB"mstr_standard"
BODY_TYPE"PLUMBING"
HDL_TAP"TRUE";
"B \NAC \NWC"4;
"S \NAC"
BN"8"166;
%"TAP"
"1","(-3150,4300)","0","mstr_standard","I200";
;
CDS_LIB"mstr_standard"
BODY_TYPE"PLUMBING"
HDL_TAP"TRUE";
"B \NAC \NWC"4;
"S \NAC"
BN"6"161;
%"TAP"
"1","(-3150,4400)","0","mstr_standard","I201";
;
CDS_LIB"mstr_standard"
BODY_TYPE"PLUMBING"
HDL_TAP"TRUE";
"B \NAC \NWC"4;
"S \NAC"
BN"7"132;
%"TAP"
"1","(-3150,4200)","0","mstr_standard","I202";
;
CDS_LIB"mstr_standard"
BODY_TYPE"PLUMBING"
HDL_TAP"TRUE";
"B \NAC \NWC"4;
"S \NAC"
BN"5"157;
%"TAP"
"1","(-3150,4100)","0","mstr_standard","I203";
;
CDS_LIB"mstr_standard"
BODY_TYPE"PLUMBING"
HDL_TAP"TRUE";
"B \NAC \NWC"4;
"S \NAC"
BN"4"153;
%"TAP"
"1","(-3150,4000)","0","mstr_standard","I204";
;
CDS_LIB"mstr_standard"
BODY_TYPE"PLUMBING"
HDL_TAP"TRUE";
"B \NAC \NWC"4;
"S \NAC"
BN"3"149;
%"TAP"
"1","(-3150,3800)","0","mstr_standard","I205";
;
CDS_LIB"mstr_standard"
BODY_TYPE"PLUMBING"
HDL_TAP"TRUE";
"B \NAC \NWC"4;
"S \NAC"
BN"1"141;
%"TAP"
"1","(-3150,3900)","0","mstr_standard","I206";
;
CDS_LIB"mstr_standard"
BODY_TYPE"PLUMBING"
HDL_TAP"TRUE";
"B \NAC \NWC"4;
"S \NAC"
BN"2"145;
%"TAP"
"1","(-3150,3700)","0","mstr_standard","I207";
;
CDS_LIB"mstr_standard"
BODY_TYPE"PLUMBING"
HDL_TAP"TRUE";
"B \NAC \NWC"4;
"S \NAC"
BN"0"137;
%"TAP"
"1","(-3150,3550)","0","mstr_standard","I208";
;
CDS_LIB"mstr_standard"
BODY_TYPE"PLUMBING"
HDL_TAP"TRUE";
"B \NAC \NWC"2;
"S \NAC"
BN"9"168;
%"TAP"
"1","(-3350,4450)","0","mstr_standard","I209";
;
CDS_LIB"mstr_standard"
BODY_TYPE"PLUMBING"
HDL_TAP"TRUE";
"B \NAC \NWC"3;
"S \NAC"
BN"7"164;
%"TAP"
"1","(-3350,4350)","0","mstr_standard","I210";
;
CDS_LIB"mstr_standard"
BODY_TYPE"PLUMBING"
HDL_TAP"TRUE";
"B \NAC \NWC"3;
"S \NAC"
BN"6"133;
%"TAP"
"1","(-3350,4250)","0","mstr_standard","I211";
;
CDS_LIB"mstr_standard"
BODY_TYPE"PLUMBING"
HDL_TAP"TRUE";
"B \NAC \NWC"3;
"S \NAC"
BN"5"158;
%"TAP"
"1","(-3350,4050)","0","mstr_standard","I212";
;
CDS_LIB"mstr_standard"
BODY_TYPE"PLUMBING"
HDL_TAP"TRUE";
"B \NAC \NWC"3;
"S \NAC"
BN"3"150;
%"TAP"
"1","(-3350,4150)","0","mstr_standard","I213";
;
CDS_LIB"mstr_standard"
BODY_TYPE"PLUMBING"
HDL_TAP"TRUE";
"B \NAC \NWC"3;
"S \NAC"
BN"4"154;
%"TAP"
"1","(-3350,3950)","0","mstr_standard","I214";
;
CDS_LIB"mstr_standard"
BODY_TYPE"PLUMBING"
HDL_TAP"TRUE";
"B \NAC \NWC"3;
"S \NAC"
BN"2"146;
%"TAP"
"1","(-3350,3850)","0","mstr_standard","I215";
;
CDS_LIB"mstr_standard"
BODY_TYPE"PLUMBING"
HDL_TAP"TRUE";
"B \NAC \NWC"3;
"S \NAC"
BN"1"142;
%"TAP"
"1","(-3350,3600)","0","mstr_standard","I216";
;
CDS_LIB"mstr_standard"
BODY_TYPE"PLUMBING"
HDL_TAP"TRUE";
"B \NAC \NWC"1;
"S \NAC"
BN"9"169;
%"TAP"
"1","(-3350,3750)","0","mstr_standard","I217";
;
CDS_LIB"mstr_standard"
BODY_TYPE"PLUMBING"
HDL_TAP"TRUE";
"B \NAC \NWC"3;
"S \NAC"
BN"0"138;
%"TAP"
"1","(-3150,3450)","0","mstr_standard","I218";
;
CDS_LIB"mstr_standard"
BODY_TYPE"PLUMBING"
HDL_TAP"TRUE";
"B \NAC \NWC"2;
"S \NAC"
BN"8"135;
%"TAP"
"1","(-3150,3350)","0","mstr_standard","I219";
;
CDS_LIB"mstr_standard"
BODY_TYPE"PLUMBING"
HDL_TAP"TRUE";
"B \NAC \NWC"2;
"S \NAC"
BN"7"165;
%"SCONN288_DDR506112002KQ"
"1","(-6700,3575)","0","pure_quanta","I22";
;
LOCATION"J29"
$SEC"1"
CDS_SEC"1"
PART_TYPE"SMLF"
VALUE"SCONN288_DDR506112002KQ"
MATERIAL"IO"
PART_NUMBER"DFHST8FS479"
CDS_LMAN_SYM_OUTLINE"-450,1900,450,-1850"
NEEDS_NO_SIZE"TRUE"
CDS_LIB"pure_quanta";
"PWR_GOOD||FAIL_N"
$PN"147"15;
"DQ31_A"
$PN"194"33;
"CB7_A"
$PN"205"34;
"CB4_A"
$PN"58"35;
"CB1_A"
$PN"53"36;
"CB7_B"
$PN"236"37;
"ALERT_N \B"
$PN"62"28;
"CA0_A"
$PN"66"38;
"CA0_B"
$PN"76"39;
"CA1_A"
$PN"211"40;
"CA1_B"
$PN"221"41;
"CA2_A"
$PN"68"42;
"CA2_B"
$PN"78"43;
"CA3_A"
$PN"213"126;
"CA3_B"
$PN"223"44;
"CA4_A"
$PN"70"45;
"CA4_B"
$PN"80"46;
"CA5_A"
$PN"215"127;
"CA5_B"
$PN"225"47;
"CA6_A"
$PN"72"128;
"CA6_B"
$PN"82"48;
"CB6_A"
$PN"203"49;
"CB5_A"
$PN"60"50;
"CB3_A"
$PN"198"51;
"CB2_A"
$PN"196"52;
"CB0_A"
$PN"51"53;
"CB6_B"
$PN"234"54;
"CB5_B"
$PN"91"55;
"CB4_B"
$PN"89"56;
"CB3_B"
$PN"243"57;
"CB2_B"
$PN"241"58;
"CB1_B"
$PN"98"59;
"CB0_B"
$PN"96"60;
"CK_C \B"
$PN"218"61;
"CK_T"
$PN"217"62;
"CS0_A_N"
$PN"64"175;
"CS0_B_N"
$PN"84"63;
"CS1_A_N"
$PN"209"64;
"CS1_B_N"
$PN"229"65;
"DQ30_A"
$PN"192"66;
"DQ29_A"
$PN"49"123;
"DQ28_A"
$PN"47"67;
"DQ27_A"
$PN"187"68;
"DQ26_A"
$PN"185"69;
"DQ25_A"
$PN"42"70;
"DQ24_A"
$PN"40"129;
"DQ23_A"
$PN"183"130;
"DQ22_A"
$PN"181"125;
"DQ21_A"
$PN"38"124;
"DQ20_A"
$PN"36"71;
"DQ19_A"
$PN"176"72;
"DQ18_A"
$PN"174"73;
"DQ17_A"
$PN"31"74;
"DQ16_A"
$PN"29"75;
"DQ15_A"
$PN"172"131;
"DQ14_A"
$PN"170"76;
"DQ13_A"
$PN"27"77;
"DQ12_A"
$PN"25"78;
"DQ11_A"
$PN"165"79;
"DQ10_A"
$PN"163"80;
"DQ9_A"
$PN"20"81;
"DQ8_A"
$PN"18"82;
"DQ7_A"
$PN"161"83;
"DQ6_A"
$PN"159"84;
"DQ5_A"
$PN"16"85;
"DQ4_A"
$PN"14"86;
"DQ3_A"
$PN"154"87;
"DQ2_A"
$PN"152"88;
"DQ1_A"
$PN"9"89;
"DQ0_A"
$PN"7"90;
"DQ31_B"
$PN"287"91;
"DQ30_B"
$PN"285"92;
"DQ29_B"
$PN"142"93;
"DQ28_B"
$PN"140"94;
"DQ27_B"
$PN"280"95;
"DQ26_B"
$PN"278"96;
"DQ25_B"
$PN"135"97;
"DQ24_B"
$PN"133"98;
"DQ23_B"
$PN"276"99;
"DQ22_B"
$PN"274"100;
"DQ21_B"
$PN"131"101;
"DQ20_B"
$PN"129"176;
"DQ19_B"
$PN"269"102;
"DQ18_B"
$PN"267"177;
"DQ17_B"
$PN"124"103;
"DQ16_B"
$PN"122"104;
"DQ15_B"
$PN"265"105;
"DQ14_B"
$PN"263"106;
"DQ13_B"
$PN"120"107;
"DQ12_B"
$PN"118"108;
"DQ11_B"
$PN"258"26;
"DQ10_B"
$PN"256"109;
"DQ9_B"
$PN"113"110;
"DQ8_B"
$PN"111"111;
"DQ7_B"
$PN"254"112;
"DQ6_B"
$PN"252"113;
"DQ5_B"
$PN"109"114;
"DQ4_B"
$PN"107"115;
"DQ3_B"
$PN"247"116;
"DQ2_B"
$PN"245"117;
"DQ1_B"
$PN"102"118;
"DQ0_B"
$PN"100"119;
"HAS"
$PN"148"18;
"HSCL"
$PN"4"16;
"HSDA"
$PN"5"17;
"LBD||RSP_A_N"
$PN"86"19;
"LBS||RSP_B_N"
$PN"87"120;
"PAR_A"
$PN"74"121;
"PAR_B"
$PN"227"122;
"RESET_N \B"
$PN"207"29;
"RFU6"
$PN"232"25;
"RFU5"
$PN"231"24;
"RFU4"
$PN"220"23;
"RFU3"
$PN"150"22;
"RFU2"
$PN"149"178;
"RFU1"
$PN"144"21;
"RFU0"
$PN"2"20;
"VIN_MGMT"
$PN"3"27;
%"TAP"
"1","(-3150,3150)","0","mstr_standard","I220";
;
CDS_LIB"mstr_standard"
BODY_TYPE"PLUMBING"
HDL_TAP"TRUE";
"B \NAC \NWC"2;
"S \NAC"
BN"5"159;
%"TAP"
"1","(-3150,3250)","0","mstr_standard","I221";
;
CDS_LIB"mstr_standard"
BODY_TYPE"PLUMBING"
HDL_TAP"TRUE";
"B \NAC \NWC"2;
"S \NAC"
BN"6"162;
%"TAP"
"1","(-3150,3050)","0","mstr_standard","I222";
;
CDS_LIB"mstr_standard"
BODY_TYPE"PLUMBING"
HDL_TAP"TRUE";
"B \NAC \NWC"2;
"S \NAC"
BN"4"155;
%"TAP"
"1","(-3150,2950)","0","mstr_standard","I223";
;
CDS_LIB"mstr_standard"
BODY_TYPE"PLUMBING"
HDL_TAP"TRUE";
"B \NAC \NWC"2;
"S \NAC"
BN"3"151;
%"TAP"
"1","(-3150,2850)","0","mstr_standard","I224";
;
CDS_LIB"mstr_standard"
BODY_TYPE"PLUMBING"
HDL_TAP"TRUE";
"B \NAC \NWC"2;
"S \NAC"
BN"2"147;
%"TAP"
"1","(-3150,2750)","0","mstr_standard","I225";
;
CDS_LIB"mstr_standard"
BODY_TYPE"PLUMBING"
HDL_TAP"TRUE";
"B \NAC \NWC"2;
"S \NAC"
BN"1"143;
%"TAP"
"1","(-3150,2650)","0","mstr_standard","I226";
;
CDS_LIB"mstr_standard"
BODY_TYPE"PLUMBING"
HDL_TAP"TRUE";
"B \NAC \NWC"2;
"S \NAC"
BN"0"139;
%"TAP"
"1","(-3350,3500)","0","mstr_standard","I227";
;
CDS_LIB"mstr_standard"
BODY_TYPE"PLUMBING"
HDL_TAP"TRUE";
"B \NAC \NWC"1;
"S \NAC"
BN"8"134;
%"TAP"
"1","(-3350,3400)","0","mstr_standard","I228";
;
CDS_LIB"mstr_standard"
BODY_TYPE"PLUMBING"
HDL_TAP"TRUE";
"B \NAC \NWC"1;
"S \NAC"
BN"7"136;
%"TAP"
"1","(-3350,3300)","0","mstr_standard","I229";
;
CDS_LIB"mstr_standard"
BODY_TYPE"PLUMBING"
HDL_TAP"TRUE";
"B \NAC \NWC"1;
"S \NAC"
BN"6"163;
%"TAP"
"1","(-7550,3125)","2","mstr_standard","I23";
;
CDS_LIB"mstr_standard"
BODY_TYPE"PLUMBING"
HDL_TAP"TRUE";
"B \NAC \NWC"8;
"S \NAC"
BN"0"60;
%"TAP"
"1","(-3350,3200)","0","mstr_standard","I230";
;
CDS_LIB"mstr_standard"
BODY_TYPE"PLUMBING"
HDL_TAP"TRUE";
"B \NAC \NWC"1;
"S \NAC"
BN"5"160;
%"TAP"
"1","(-3350,3100)","0","mstr_standard","I231";
;
CDS_LIB"mstr_standard"
BODY_TYPE"PLUMBING"
HDL_TAP"TRUE";
"B \NAC \NWC"1;
"S \NAC"
BN"4"156;
%"TAP"
"1","(-3350,2900)","0","mstr_standard","I232";
;
CDS_LIB"mstr_standard"
BODY_TYPE"PLUMBING"
HDL_TAP"TRUE";
"B \NAC \NWC"1;
"S \NAC"
BN"2"148;
%"TAP"
"1","(-3350,3000)","0","mstr_standard","I233";
;
CDS_LIB"mstr_standard"
BODY_TYPE"PLUMBING"
HDL_TAP"TRUE";
"B \NAC \NWC"1;
"S \NAC"
BN"3"152;
%"TAP"
"1","(-3350,2800)","0","mstr_standard","I234";
;
CDS_LIB"mstr_standard"
BODY_TYPE"PLUMBING"
HDL_TAP"TRUE";
"B \NAC \NWC"1;
"S \NAC"
BN"1"144;
%"TAP"
"1","(-3350,2700)","0","mstr_standard","I235";
;
CDS_LIB"mstr_standard"
BODY_TYPE"PLUMBING"
HDL_TAP"TRUE";
"B \NAC \NWC"1;
"S \NAC"
BN"0"140;
%"SCONN288_DDR506112002KQ"
"2","(-4300,3650)","0","pure_quanta","I236";
;
LOCATION"J29"
$SEC"2"
CDS_SEC"2"
VALUE"SCONN288_DDR506112002KQ"
PART_TYPE"SMLF"
MATERIAL"IO"
PART_NUMBER"DFHST8FS479"
CDS_LMAN_SYM_OUTLINE"-600,1150,600,-1150"
NEEDS_NO_SIZE"TRUE"
CDS_LIB"pure_quanta";
"DQS7_A_C||TDQS7_A_C \B"
$PN"178"132;
"DQS6_A_T||TDQS6_A_T"
$PN"168"133;
"DQS8_B_T||TDQS8_B_T"
$PN"283"134;
"DQS8_B_C||TDQS8_B_C \B"
$PN"282"135;
"DQS7_B_T||TDQS7_B_T"
$PN"272"136;
"DQS0_A_C \B"
$PN"12"137;
"DQS0_A_T"
$PN"11"138;
"DQS0_B_C \B"
$PN"105"139;
"DQS0_B_T"
$PN"104"140;
"DQS1_A_C \B"
$PN"23"141;
"DQS1_A_T"
$PN"22"142;
"DQS1_B_C \B"
$PN"116"143;
"DQS1_B_T"
$PN"115"144;
"DQS2_A_C \B"
$PN"34"145;
"DQS2_A_T"
$PN"33"146;
"DQS2_B_C \B"
$PN"127"147;
"DQS2_B_T"
$PN"126"148;
"DQS3_A_C \B"
$PN"45"149;
"DQS3_A_T"
$PN"44"150;
"DQS3_B_C \B"
$PN"138"151;
"DQS3_B_T"
$PN"137"152;
"DQS4_A_C \B"
$PN"56"153;
"DQS4_A_T"
$PN"55"154;
"DQS4_B_C \B"
$PN"238"155;
"DQS4_B_T"
$PN"239"156;
"DQS5_A_C||TDQS5_A_C||DQS5_A_T||TDQS5_A_T \B"
$PN"156"157;
"DQS5_A_T||TDQS5_A_T"
$PN"157"158;
"DQS5_B_C||TDQS5_B_C \B"
$PN"249"159;
"DQS5_B_T||TDQS5_B_T"
$PN"250"160;
"DQS6_A_C||TDQS6_A_C||DQS6_A_T||TDQS6_A_T \B"
$PN"167"161;
"DQS6_B_C||TDQS6_B_C \B"
$PN"260"162;
"DQS6_B_T||TDQS6_B_T"
$PN"261"163;
"DQS7_A_T||TDQS7_A_T"
$PN"179"164;
"DQS7_B_C||TDQS7_B_C \B"
$PN"271"165;
"DQS8_A_C||TDQS8_A_C \B"
$PN"189"166;
"DQS8_A_T||TDQS8_A_T"
$PN"190"167;
"DQS9_A_C||TDQS9_A_C \B"
$PN"200"170;
"DQS9_A_T||TDQS9_A_T"
$PN"201"171;
"DQS9_B_C||TDQS9_B_C \B"
$PN"94"168;
"DQS9_B_T||TDQS9_B_T||DBI4_B_N"
$PN"93"169;
%"GND"
"1","(-2725,5425)","0","pure_quanta_power","I237";
;
CDS_LIB"pure_quanta_power"
BOM_COST"MEM"
SIZE"1B"
ROOM"MEM_EFGH_DECOUPLING_CAPS"
HDL_POWER"GND";
"A<SIZE-1..0>\NAC"30;
%"Q_CAP"
"1","(-2725,5775)","2","pure_quanta","I238";
;
LOCATION"C536"
$SEC"1"
CDS_SEC"1"
MATERIAL"X6S"
TOLERANCE"10%"
VALUE"10UF"
PART_NUMBER"CH6104KEA00"
VOLTAGE"25V"
PACK_TYPE"C0805"
BOM_COST"MEM"
CDS_LIB"pure_quanta"
ROOM"MEM_CH_A_CPU0_DIMM1";
"B"
$PN"2"30;
"A"
$PN"1"172;
%"Q_CAP"
"1","(-2150,5775)","2","pure_quanta","I239";
;
LOCATION"C537"
$SEC"1"
CDS_SEC"1"
MATERIAL"X6S"
TOLERANCE"10%"
VALUE"10UF"
PART_NUMBER"CH6104KEA00"
VOLTAGE"25V"
PACK_TYPE"C0805"
BOM_COST"MEM"
CDS_LIB"pure_quanta"
ROOM"MEM_CH_A_CPU0_DIMM1";
"B"
$PN"2"30;
"A"
$PN"1"172;
%"TAP"
"1","(-7550,3175)","2","mstr_standard","I24";
;
CDS_LIB"mstr_standard"
BODY_TYPE"PLUMBING"
HDL_TAP"TRUE";
"B \NAC \NWC"8;
"S \NAC"
BN"1"59;
%"UNIVERSAL_POWER"
"1","(-2725,6100)","0","pure_quanta_power","I240";
;
HDL_POWER"P12V_MEM_1"
CDS_LIB"pure_quanta_power";
"A"172;
%"Q_RES"
"1","(-7600,2625)","0","pure_quanta","I242";
;
$LOCATION"R1589"
CDS_LOCATION"R1589"
$SEC"1"
CDS_SEC"1"
VALUE"49.9"
CDS_LIB"pure_quanta"
MATERIAL"CHIP"
PACK_TYPE"0402LF"
WATTAGE"1/16W"
TOLERANCE"1%"
PART_NUMBER"CS04992FB07";
"B"
$PN"2"16;
"A"
$PN"1"14;
%"TAP"
"1","(-7550,3225)","2","mstr_standard","I25";
;
CDS_LIB"mstr_standard"
BODY_TYPE"PLUMBING"
HDL_TAP"TRUE";
"B \NAC \NWC"8;
"S \NAC"
BN"2"58;
%"TAP"
"1","(-7550,3325)","2","mstr_standard","I26";
;
CDS_LIB"mstr_standard"
BODY_TYPE"PLUMBING"
HDL_TAP"TRUE";
"B \NAC \NWC"8;
"S \NAC"
BN"4"56;
%"TAP"
"1","(-7550,3275)","2","mstr_standard","I27";
;
CDS_LIB"mstr_standard"
BODY_TYPE"PLUMBING"
HDL_TAP"TRUE";
"B \NAC \NWC"8;
"S \NAC"
BN"3"57;
%"TAP"
"1","(-7550,3375)","2","mstr_standard","I28";
;
CDS_LIB"mstr_standard"
BODY_TYPE"PLUMBING"
HDL_TAP"TRUE";
"B \NAC \NWC"8;
"S \NAC"
BN"5"55;
%"TAP"
"1","(-7550,3425)","2","mstr_standard","I29";
;
CDS_LIB"mstr_standard"
BODY_TYPE"PLUMBING"
HDL_TAP"TRUE";
"B \NAC \NWC"8;
"S \NAC"
BN"6"54;
%"TAP"
"1","(-7550,3475)","2","mstr_standard","I30";
;
CDS_LIB"mstr_standard"
BODY_TYPE"PLUMBING"
HDL_TAP"TRUE";
"B \NAC \NWC"8;
"S \NAC"
BN"7"37;
%"TAP"
"1","(-7550,3575)","2","mstr_standard","I31";
;
CDS_LIB"mstr_standard"
BODY_TYPE"PLUMBING"
HDL_TAP"TRUE";
"B \NAC \NWC"9;
"S \NAC"
BN"0"53;
%"TAP"
"1","(-7550,3625)","2","mstr_standard","I32";
;
CDS_LIB"mstr_standard"
BODY_TYPE"PLUMBING"
HDL_TAP"TRUE";
"B \NAC \NWC"9;
"S \NAC"
BN"1"36;
%"TAP"
"1","(-7550,3675)","2","mstr_standard","I33";
;
CDS_LIB"mstr_standard"
BODY_TYPE"PLUMBING"
HDL_TAP"TRUE";
"B \NAC \NWC"9;
"S \NAC"
BN"2"52;
%"TAP"
"1","(-7550,3725)","2","mstr_standard","I34";
;
CDS_LIB"mstr_standard"
BODY_TYPE"PLUMBING"
HDL_TAP"TRUE";
"B \NAC \NWC"9;
"S \NAC"
BN"3"51;
%"TAP"
"1","(-7550,3825)","2","mstr_standard","I35";
;
CDS_LIB"mstr_standard"
BODY_TYPE"PLUMBING"
HDL_TAP"TRUE";
"B \NAC \NWC"9;
"S \NAC"
BN"5"50;
%"TAP"
"1","(-7550,3775)","2","mstr_standard","I36";
;
CDS_LIB"mstr_standard"
BODY_TYPE"PLUMBING"
HDL_TAP"TRUE";
"B \NAC \NWC"9;
"S \NAC"
BN"4"35;
%"TAP"
"1","(-5850,2125)","0","mstr_standard","I37";
;
CDS_LIB"mstr_standard"
BODY_TYPE"PLUMBING"
HDL_TAP"TRUE";
"B \NAC \NWC"7;
"S \NAC"
BN"0"119;
%"TAP"
"1","(-5850,2175)","0","mstr_standard","I38";
;
CDS_LIB"mstr_standard"
BODY_TYPE"PLUMBING"
HDL_TAP"TRUE";
"B \NAC \NWC"7;
"S \NAC"
BN"1"118;
%"TAP"
"1","(-5850,2225)","0","mstr_standard","I39";
;
CDS_LIB"mstr_standard"
BODY_TYPE"PLUMBING"
HDL_TAP"TRUE";
"B \NAC \NWC"7;
"S \NAC"
BN"2"117;
%"TAP"
"1","(-5850,2275)","0","mstr_standard","I40";
;
CDS_LIB"mstr_standard"
BODY_TYPE"PLUMBING"
HDL_TAP"TRUE";
"B \NAC \NWC"7;
"S \NAC"
BN"3"116;
%"TAP"
"1","(-5850,2325)","0","mstr_standard","I41";
;
CDS_LIB"mstr_standard"
BODY_TYPE"PLUMBING"
HDL_TAP"TRUE";
"B \NAC \NWC"7;
"S \NAC"
BN"4"115;
%"TAP"
"1","(-5850,2425)","0","mstr_standard","I42";
;
CDS_LIB"mstr_standard"
BODY_TYPE"PLUMBING"
HDL_TAP"TRUE";
"B \NAC \NWC"7;
"S \NAC"
BN"6"113;
%"TAP"
"1","(-5850,2375)","0","mstr_standard","I43";
;
CDS_LIB"mstr_standard"
BODY_TYPE"PLUMBING"
HDL_TAP"TRUE";
"B \NAC \NWC"7;
"S \NAC"
BN"5"114;
%"TAP"
"1","(-5850,2525)","0","mstr_standard","I44";
;
CDS_LIB"mstr_standard"
BODY_TYPE"PLUMBING"
HDL_TAP"TRUE";
"B \NAC \NWC"7;
"S \NAC"
BN"8"111;
%"TAP"
"1","(-5850,2475)","0","mstr_standard","I45";
;
CDS_LIB"mstr_standard"
BODY_TYPE"PLUMBING"
HDL_TAP"TRUE";
"B \NAC \NWC"7;
"S \NAC"
BN"7"112;
%"TAP"
"1","(-5850,2575)","0","mstr_standard","I46";
;
CDS_LIB"mstr_standard"
BODY_TYPE"PLUMBING"
HDL_TAP"TRUE";
"B \NAC \NWC"7;
"S \NAC"
BN"9"110;
%"TAP"
"1","(-5850,2675)","0","mstr_standard","I47";
;
CDS_LIB"mstr_standard"
BODY_TYPE"PLUMBING"
HDL_TAP"TRUE";
"B \NAC \NWC"7;
"S \NAC"
BN"11"26;
%"TAP"
"1","(-5850,2625)","0","mstr_standard","I48";
;
CDS_LIB"mstr_standard"
BODY_TYPE"PLUMBING"
HDL_TAP"TRUE";
"B \NAC \NWC"7;
"S \NAC"
BN"10"109;
%"TAP"
"1","(-5850,2725)","0","mstr_standard","I49";
;
CDS_LIB"mstr_standard"
BODY_TYPE"PLUMBING"
HDL_TAP"TRUE";
"B \NAC \NWC"7;
"S \NAC"
BN"12"108;
%"TAP"
"1","(-5850,2775)","0","mstr_standard","I50";
;
CDS_LIB"mstr_standard"
BODY_TYPE"PLUMBING"
HDL_TAP"TRUE";
"B \NAC \NWC"7;
"S \NAC"
BN"13"107;
%"TAP"
"1","(-5850,2825)","0","mstr_standard","I51";
;
CDS_LIB"mstr_standard"
BODY_TYPE"PLUMBING"
HDL_TAP"TRUE";
"B \NAC \NWC"7;
"S \NAC"
BN"14"106;
%"TAP"
"1","(-5850,2925)","0","mstr_standard","I52";
;
CDS_LIB"mstr_standard"
BODY_TYPE"PLUMBING"
HDL_TAP"TRUE";
"B \NAC \NWC"7;
"S \NAC"
BN"16"104;
%"TAP"
"1","(-5850,2875)","0","mstr_standard","I53";
;
CDS_LIB"mstr_standard"
BODY_TYPE"PLUMBING"
HDL_TAP"TRUE";
"B \NAC \NWC"7;
"S \NAC"
BN"15"105;
%"TAP"
"1","(-5850,2975)","0","mstr_standard","I54";
;
CDS_LIB"mstr_standard"
BODY_TYPE"PLUMBING"
HDL_TAP"TRUE";
"B \NAC \NWC"7;
"S \NAC"
BN"17"103;
%"TAP"
"1","(-5850,3025)","0","mstr_standard","I55";
;
CDS_LIB"mstr_standard"
BODY_TYPE"PLUMBING"
HDL_TAP"TRUE";
"B \NAC \NWC"7;
"S \NAC"
BN"18"177;
%"TAP"
"1","(-5850,3075)","0","mstr_standard","I56";
;
CDS_LIB"mstr_standard"
BODY_TYPE"PLUMBING"
HDL_TAP"TRUE";
"B \NAC \NWC"7;
"S \NAC"
BN"19"102;
%"TAP"
"1","(-5850,3125)","0","mstr_standard","I57";
;
CDS_LIB"mstr_standard"
BODY_TYPE"PLUMBING"
HDL_TAP"TRUE";
"B \NAC \NWC"7;
"S \NAC"
BN"20"176;
%"TAP"
"1","(-5850,3175)","0","mstr_standard","I58";
;
CDS_LIB"mstr_standard"
BODY_TYPE"PLUMBING"
HDL_TAP"TRUE";
"B \NAC \NWC"7;
"S \NAC"
BN"21"101;
%"TAP"
"1","(-5850,3225)","0","mstr_standard","I59";
;
CDS_LIB"mstr_standard"
BODY_TYPE"PLUMBING"
HDL_TAP"TRUE";
"B \NAC \NWC"7;
"S \NAC"
BN"22"100;
%"TAP"
"1","(-5850,3325)","0","mstr_standard","I60";
;
CDS_LIB"mstr_standard"
BODY_TYPE"PLUMBING"
HDL_TAP"TRUE";
"B \NAC \NWC"7;
"S \NAC"
BN"24"98;
%"TAP"
"1","(-5850,3275)","0","mstr_standard","I61";
;
CDS_LIB"mstr_standard"
BODY_TYPE"PLUMBING"
HDL_TAP"TRUE";
"B \NAC \NWC"7;
"S \NAC"
BN"23"99;
%"TAP"
"1","(-5850,3375)","0","mstr_standard","I62";
;
CDS_LIB"mstr_standard"
BODY_TYPE"PLUMBING"
HDL_TAP"TRUE";
"B \NAC \NWC"7;
"S \NAC"
BN"25"97;
%"TAP"
"1","(-5850,3425)","0","mstr_standard","I63";
;
CDS_LIB"mstr_standard"
BODY_TYPE"PLUMBING"
HDL_TAP"TRUE";
"B \NAC \NWC"7;
"S \NAC"
BN"26"96;
%"TAP"
"1","(-5850,3475)","0","mstr_standard","I64";
;
CDS_LIB"mstr_standard"
BODY_TYPE"PLUMBING"
HDL_TAP"TRUE";
"B \NAC \NWC"7;
"S \NAC"
BN"27"95;
%"TAP"
"1","(-5850,3575)","0","mstr_standard","I65";
;
CDS_LIB"mstr_standard"
BODY_TYPE"PLUMBING"
HDL_TAP"TRUE";
"B \NAC \NWC"7;
"S \NAC"
BN"29"93;
%"TAP"
"1","(-5850,3525)","0","mstr_standard","I66";
;
CDS_LIB"mstr_standard"
BODY_TYPE"PLUMBING"
HDL_TAP"TRUE";
"B \NAC \NWC"7;
"S \NAC"
BN"28"94;
%"TAP"
"1","(-5850,3675)","0","mstr_standard","I67";
;
CDS_LIB"mstr_standard"
BODY_TYPE"PLUMBING"
HDL_TAP"TRUE";
"B \NAC \NWC"7;
"S \NAC"
BN"31"91;
%"TAP"
"1","(-5850,3625)","0","mstr_standard","I68";
;
CDS_LIB"mstr_standard"
BODY_TYPE"PLUMBING"
HDL_TAP"TRUE";
"B \NAC \NWC"7;
"S \NAC"
BN"30"92;
%"TAP"
"1","(-5850,3775)","0","mstr_standard","I69";
;
CDS_LIB"mstr_standard"
BODY_TYPE"PLUMBING"
HDL_TAP"TRUE";
"B \NAC \NWC"5;
"S \NAC"
BN"0"90;
%"VCC_CORE"
"1","(-8425,3350)","0","mstr_symbols","I7";
;
HDL_POWER"P3V3_STBY"
CDS_LIB"mstr_symbols"
VOLTAGE"3.3"
ROOM"PVCCINFAON_CPU1_CTRL";
"A"27;
%"TAP"
"1","(-5850,3825)","0","mstr_standard","I70";
;
CDS_LIB"mstr_standard"
BODY_TYPE"PLUMBING"
HDL_TAP"TRUE";
"B \NAC \NWC"5;
"S \NAC"
BN"1"89;
%"TAP"
"1","(-7550,3875)","2","mstr_standard","I79";
;
CDS_LIB"mstr_standard"
BODY_TYPE"PLUMBING"
HDL_TAP"TRUE";
"B \NAC \NWC"9;
"S \NAC"
BN"6"49;
%"TAP"
"1","(-7550,3925)","2","mstr_standard","I80";
;
CDS_LIB"mstr_standard"
BODY_TYPE"PLUMBING"
HDL_TAP"TRUE";
"B \NAC \NWC"9;
"S \NAC"
BN"7"34;
%"TAP"
"1","(-7550,4625)","2","mstr_standard","I81";
;
CDS_LIB"mstr_standard"
BODY_TYPE"PLUMBING"
HDL_TAP"TRUE";
"B \NAC \NWC"10;
"S \NAC"
BN"0"39;
%"TAP"
"1","(-7550,4725)","2","mstr_standard","I82";
;
CDS_LIB"mstr_standard"
BODY_TYPE"PLUMBING"
HDL_TAP"TRUE";
"B \NAC \NWC"10;
"S \NAC"
BN"2"43;
%"TAP"
"1","(-7550,4675)","2","mstr_standard","I83";
;
CDS_LIB"mstr_standard"
BODY_TYPE"PLUMBING"
HDL_TAP"TRUE";
"B \NAC \NWC"10;
"S \NAC"
BN"1"41;
%"TAP"
"1","(-7550,4825)","2","mstr_standard","I84";
;
CDS_LIB"mstr_standard"
BODY_TYPE"PLUMBING"
HDL_TAP"TRUE";
"B \NAC \NWC"10;
"S \NAC"
BN"4"46;
%"TAP"
"1","(-7550,4775)","2","mstr_standard","I85";
;
CDS_LIB"mstr_standard"
BODY_TYPE"PLUMBING"
HDL_TAP"TRUE";
"B \NAC \NWC"10;
"S \NAC"
BN"3"44;
%"TAP"
"1","(-7550,4875)","2","mstr_standard","I86";
;
CDS_LIB"mstr_standard"
BODY_TYPE"PLUMBING"
HDL_TAP"TRUE";
"B \NAC \NWC"10;
"S \NAC"
BN"5"47;
%"TAP"
"1","(-7550,4925)","2","mstr_standard","I87";
;
CDS_LIB"mstr_standard"
BODY_TYPE"PLUMBING"
HDL_TAP"TRUE";
"B \NAC \NWC"10;
"S \NAC"
BN"6"48;
%"TAP"
"1","(-7550,5025)","2","mstr_standard","I88";
;
CDS_LIB"mstr_standard"
BODY_TYPE"PLUMBING"
HDL_TAP"TRUE";
"B \NAC \NWC"6;
"S \NAC"
BN"0"38;
%"TAP"
"1","(-7550,5075)","2","mstr_standard","I89";
;
CDS_LIB"mstr_standard"
BODY_TYPE"PLUMBING"
HDL_TAP"TRUE";
"B \NAC \NWC"6;
"S \NAC"
BN"1"40;
%"TAP"
"1","(-7550,5125)","2","mstr_standard","I90";
;
CDS_LIB"mstr_standard"
BODY_TYPE"PLUMBING"
HDL_TAP"TRUE";
"B \NAC \NWC"6;
"S \NAC"
BN"2"42;
%"TAP"
"1","(-7550,5175)","2","mstr_standard","I91";
;
CDS_LIB"mstr_standard"
BODY_TYPE"PLUMBING"
HDL_TAP"TRUE";
"B \NAC \NWC"6;
"S \NAC"
BN"3"126;
%"TAP"
"1","(-7550,5225)","2","mstr_standard","I92";
;
CDS_LIB"mstr_standard"
BODY_TYPE"PLUMBING"
HDL_TAP"TRUE";
"B \NAC \NWC"6;
"S \NAC"
BN"4"45;
%"TAP"
"1","(-7550,5275)","2","mstr_standard","I93";
;
CDS_LIB"mstr_standard"
BODY_TYPE"PLUMBING"
HDL_TAP"TRUE";
"B \NAC \NWC"6;
"S \NAC"
BN"5"127;
%"TAP"
"1","(-7550,5325)","2","mstr_standard","I94";
;
CDS_LIB"mstr_standard"
BODY_TYPE"PLUMBING"
HDL_TAP"TRUE";
"B \NAC \NWC"6;
"S \NAC"
BN"6"128;
%"TAP"
"1","(-5850,3875)","0","mstr_standard","I95";
;
CDS_LIB"mstr_standard"
BODY_TYPE"PLUMBING"
HDL_TAP"TRUE";
"B \NAC \NWC"5;
"S \NAC"
BN"2"88;
%"TAP"
"1","(-5850,3925)","0","mstr_standard","I96";
;
CDS_LIB"mstr_standard"
BODY_TYPE"PLUMBING"
HDL_TAP"TRUE";
"B \NAC \NWC"5;
"S \NAC"
BN"3"87;
%"TAP"
"1","(-5850,3975)","0","mstr_standard","I97";
;
CDS_LIB"mstr_standard"
BODY_TYPE"PLUMBING"
HDL_TAP"TRUE";
"B \NAC \NWC"5;
"S \NAC"
BN"4"86;
%"TAP"
"1","(-5850,4025)","0","mstr_standard","I98";
;
CDS_LIB"mstr_standard"
BODY_TYPE"PLUMBING"
HDL_TAP"TRUE";
"B \NAC \NWC"5;
"S \NAC"
BN"5"85;
%"TAP"
"1","(-5850,4075)","0","mstr_standard","I99";
;
CDS_LIB"mstr_standard"
BODY_TYPE"PLUMBING"
HDL_TAP"TRUE";
"B \NAC \NWC"5;
"S \NAC"
BN"6"84;
END.
